# BASEBOARD_FAB2 (Tioga Pass) — schematic netlist excerpt (pin names and nets, part order shuffled) for the footprints in the layout excerpt that follows; sources: Cadence DE-HDL packaged netlist, KiCad conversion of Wiwynn_Tioga_Pass_MB.brd

C3M25  CAP  0.22UF 16V 10% X7R  pkg 0402  page 105 : A = P3E_CPU0_PE1_PCH_R_RXP<11> ; B = P3E_CPU0_PE1_PCH_RXP<11>
C10W2  CAP_A  0.1UF 16V 10% X7R  pkg 0402V  page 251 : A = P12V_PUMP ; B = GND
C30W1  CAP_A  0.1UF 16V 10% X7R  pkg 0402V  page 253 : A = USB3_P01_TXN ; B = USB3_P01_C_TXN

(kicad_pcb
	(version 20260206)
	(generator "pcbnew")
	(generator_version "10.0")
	(general
		(thickness 1.6)
		(legacy_teardrops no)
	)
	(paper "A4")
	(title_block
		(title "Wiwynn_Tioga_Pass_MB.brd")
		(comment 1 "Tioga Pass / footprints 4469-4471 of 4770")
	)
	(layers
		(0 "F.Cu" signal "TOP")
		(4 "In1.Cu" signal "L2GND")
		(6 "In2.Cu" signal "L3")
		(8 "In3.Cu" signal "L4GND")
		(10 "In4.Cu" signal "L5")
		(12 "In5.Cu" signal "L6GND")
		(14 "In6.Cu" signal "L7VCC")
		(16 "In7.Cu" signal "L8VCC")
		(18 "In8.Cu" signal "L9GND")
		(20 "In9.Cu" signal "L10")
		(22 "In10.Cu" signal "L11GND")
		(24 "In11.Cu" signal "L12")
		(26 "In12.Cu" signal "L13GND")
		(2 "B.Cu" signal "BOTTOM")
		(9 "F.Adhes" user "F.Adhesive")
		(11 "B.Adhes" user "B.Adhesive")
		(13 "F.Paste" user "Package Geometry/Pastemask Top")
		(15 "B.Paste" user "Package Geometry/Pastemask Bottom")
		(5 "F.SilkS" user "Ref Des/Silkscreen Top")
		(7 "B.SilkS" user "Ref Des/Silkscreen Bottom")
		(1 "F.Mask" user "Board Geometry/Soldermask Top")
		(3 "B.Mask" user "Board Geometry/Soldermask Bottom")
		(17 "Dwgs.User" user "User.Drawings")
		(19 "Cmts.User" user "User.Comments")
		(21 "Eco1.User" user "User.Eco1")
		(23 "Eco2.User" user "User.Eco2")
		(25 "Edge.Cuts" user "Board Geometry/Outline")
		(27 "Margin" user)
		(31 "F.CrtYd" user "Package Geometry/Place Bound Top")
		(29 "B.CrtYd" user "Package Geometry/Place Bound Bottom")
		(35 "F.Fab" user "Ref Des/Assembly Top")
		(33 "B.Fab" user "Ref Des/Assembly Bottom")
	)
	(footprint ""
		(layer "B.Cu")
		(at 13.360654 -122.704098 180)
		(property "Reference" "C10W2"
			(at 0.8382 -0.67818 180)
			(unlocked yes)
			(layer "B.SilkS")
			(effects
				(font
					(size 0.4064 0.254)
					(thickness 0.1524)
				)
				(justify left mirror)
			)
		)
		(property "Value" ""
			(at 0 0 0)
			(layer "B.Fab")
			(effects
				(font
					(size 1.27 1.27)
				)
				(justify mirror)
			)
		)
		(duplicate_pad_numbers_are_jumpers no)
		(fp_poly
			(pts
				(xy -0.3048 -0.1016) (xy -0.3048 0.9906) (xy 0.3048 0.9906) (xy 0.3048 -0.1016)
			)
			(stroke
				(width 0)
				(type default)
			)
			(fill no)
			(layer "B.CrtYd")
		)
		(fp_line
			(start 0.3048 0.9906)
			(end -0.3048 0.9906)
			(stroke
				(width 0.1)
				(type default)
			)
			(layer "B.Fab")
		)
		(fp_line
			(start 0.3048 -0.1016)
			(end 0.3048 0.9906)
			(stroke
				(width 0.1)
				(type default)
			)
			(layer "B.Fab")
		)
		(fp_line
			(start -0.3048 0.9906)
			(end -0.3048 -0.1016)
			(stroke
				(width 0.1)
				(type default)
			)
			(layer "B.Fab")
		)
		(fp_line
			(start -0.3048 -0.1016)
			(end 0.3048 -0.1016)
			(stroke
				(width 0.1)
				(type default)
			)
			(layer "B.Fab")
		)
		(pad "1" smd rect
			(at 0 0)
			(size 0.508 0.508)
			(layers "B.Cu" "B.Mask" "B.Paste")
			(net "P12V_PUMP")
		)
		(pad "2" smd rect
			(at 0 0.889)
			(size 0.508 0.508)
			(layers "B.Cu" "B.Mask" "B.Paste")
			(net "GND")
		)
		(zone
			(layer "B.Cu")
			(hatch none 0.5)
			(connect_pads
				(clearance 0)
			)
			(min_thickness 0.25)
			(keepout
				(tracks not_allowed)
				(vias allowed)
				(pads allowed)
				(copperpour not_allowed)
				(footprints allowed)
			)
			(placement
				(enabled no)
				(sheetname "")
			)
			(fill
				(thermal_gap 0.5)
				(thermal_bridge_width 0.5)
				(island_removal_mode 0)
			)
			(polygon
				(pts
					(xy 13.106654 -123.339098) (xy 13.614654 -123.339098) (xy 13.614654 -122.958098) (xy 13.106654 -122.958098)
				)
			)
		)
		(zone
			(layer "B.Cu")
			(hatch none 0.5)
			(connect_pads
				(clearance 0)
			)
			(min_thickness 0.25)
			(keepout
				(tracks allowed)
				(vias not_allowed)
				(pads allowed)
				(copperpour not_allowed)
				(footprints allowed)
			)
			(placement
				(enabled no)
				(sheetname "")
			)
			(fill
				(thermal_gap 0.5)
				(thermal_bridge_width 0.5)
				(island_removal_mode 0)
			)
			(polygon
				(pts
					(xy 13.106654 -122.958098) (xy 13.614654 -122.958098) (xy 13.614654 -123.339098) (xy 13.106654 -123.339098)
				)
			)
		)
	)
	(footprint ""
		(layer "B.Cu")
		(at 485.25938 -60.822332 90)
		(property "Reference" "C30W1"
			(at 0.8382 -0.67818 90)
			(unlocked yes)
			(layer "B.SilkS")
			(effects
				(font
					(size 0.4064 0.254)
					(thickness 0.1524)
				)
				(justify left mirror)
			)
		)
		(property "Value" ""
			(at 0 0 90)
			(layer "B.Fab")
			(effects
				(font
					(size 1.27 1.27)
				)
				(justify mirror)
			)
		)
		(duplicate_pad_numbers_are_jumpers no)
		(fp_poly
			(pts
				(xy -0.3048 -0.1016) (xy -0.3048 0.9906) (xy 0.3048 0.9906) (xy 0.3048 -0.1016)
			)
			(stroke
				(width 0)
				(type default)
			)
			(fill no)
			(layer "B.CrtYd")
		)
		(fp_line
			(start 0.3048 -0.1016)
			(end 0.3048 0.9906)
			(stroke
				(width 0.1)
				(type default)
			)
			(layer "B.Fab")
		)
		(fp_line
			(start -0.3048 -0.1016)
			(end 0.3048 -0.1016)
			(stroke
				(width 0.1)
				(type default)
			)
			(layer "B.Fab")
		)
		(fp_line
			(start 0.3048 0.9906)
			(end -0.3048 0.9906)
			(stroke
				(width 0.1)
				(type default)
			)
			(layer "B.Fab")
		)
		(fp_line
			(start -0.3048 0.9906)
			(end -0.3048 -0.1016)
			(stroke
				(width 0.1)
				(type default)
			)
			(layer "B.Fab")
		)
		(pad "1" smd rect
			(at 0 0 270)
			(size 0.508 0.508)
			(layers "B.Cu" "B.Mask" "B.Paste")
			(net "USB3_P01_TXN")
		)
		(pad "2" smd rect
			(at 0 0.889 270)
			(size 0.508 0.508)
			(layers "B.Cu" "B.Mask" "B.Paste")
			(net "USB3_P01_C_TXN")
		)
		(zone
			(layer "B.Cu")
			(hatch none 0.5)
			(connect_pads
				(clearance 0)
			)
			(min_thickness 0.25)
			(keepout
				(tracks allowed)
				(vias not_allowed)
				(pads allowed)
				(copperpour not_allowed)
				(footprints allowed)
			)
			(placement
				(enabled no)
				(sheetname "")
			)
			(fill
				(thermal_gap 0.5)
				(thermal_bridge_width 0.5)
				(island_removal_mode 0)
			)
			(polygon
				(pts
					(xy 485.51338 -61.076332) (xy 485.51338 -60.568332) (xy 485.89438 -60.568332) (xy 485.89438 -61.076332)
				)
			)
		)
		(zone
			(layer "B.Cu")
			(hatch none 0.5)
			(connect_pads
				(clearance 0)
			)
			(min_thickness 0.25)
			(keepout
				(tracks not_allowed)
				(vias allowed)
				(pads allowed)
				(copperpour not_allowed)
				(footprints allowed)
			)
			(placement
				(enabled no)
				(sheetname "")
			)
			(fill
				(thermal_gap 0.5)
				(thermal_bridge_width 0.5)
				(island_removal_mode 0)
			)
			(polygon
				(pts
					(xy 485.89438 -61.076332) (xy 485.89438 -60.568332) (xy 485.51338 -60.568332) (xy 485.51338 -61.076332)
				)
			)
		)
	)
	(footprint ""
		(layer "B.Cu")
		(at 362.715556 -121.392442 -90)
		(property "Reference" "C3M25"
			(at 0 0 90)
			(layer "B.SilkS")
			(hide yes)
			(effects
				(font
					(size 1.27 1.27)
				)
				(justify mirror)
			)
		)
		(property "Value" ""
			(at 0 0 90)
			(layer "B.Fab")
			(effects
				(font
					(size 1.27 1.27)
				)
				(justify mirror)
			)
		)
		(duplicate_pad_numbers_are_jumpers no)
		(fp_poly
			(pts
				(xy -0.3048 -0.1016) (xy -0.3048 0.9906) (xy 0.3048 0.9906) (xy 0.3048 -0.1016)
			)
			(stroke
				(width 0)
				(type default)
			)
			(fill no)
			(layer "B.CrtYd")
		)
		(fp_line
			(start -0.3048 0.9906)
			(end -0.3048 -0.1016)
			(stroke
				(width 0.1)
				(type default)
			)
			(layer "B.Fab")
		)
		(fp_line
			(start 0.3048 0.9906)
			(end -0.3048 0.9906)
			(stroke
				(width 0.1)
				(type default)
			)
			(layer "B.Fab")
		)
		(fp_line
			(start -0.3048 -0.1016)
			(end 0.3048 -0.1016)
			(stroke
				(width 0.1)
				(type default)
			)
			(layer "B.Fab")
		)
		(fp_line
			(start 0.3048 -0.1016)
			(end 0.3048 0.9906)
			(stroke
				(width 0.1)
				(type default)
			)
			(layer "B.Fab")
		)
		(pad "1" smd rect
			(at 0 0 90)
			(size 0.508 0.508)
			(layers "B.Cu" "B.Mask" "B.Paste")
			(net "P3E_CPU0_PE1_PCH_R_RXP<11>")
		)
		(pad "2" smd rect
			(at 0 0.889 90)
			(size 0.508 0.508)
			(layers "B.Cu" "B.Mask" "B.Paste")
			(net "P3E_CPU0_PE1_PCH_RXP<11>")
		)
		(zone
			(layer "B.Cu")
			(hatch none 0.5)
			(connect_pads
				(clearance 0)
			)
			(min_thickness 0.25)
			(keepout
				(tracks not_allowed)
				(vias allowed)
				(pads allowed)
				(copperpour not_allowed)
				(footprints allowed)
			)
			(placement
				(enabled no)
				(sheetname "")
			)
			(fill
				(thermal_gap 0.5)
				(thermal_bridge_width 0.5)
				(island_removal_mode 0)
			)
			(polygon
				(pts
					(xy 362.080556 -121.138442) (xy 362.080556 -121.646442) (xy 362.461556 -121.646442) (xy 362.461556 -121.138442)
				)
			)
		)
		(zone
			(layer "B.Cu")
			(hatch none 0.5)
			(connect_pads
				(clearance 0)
			)
			(min_thickness 0.25)
			(keepout
				(tracks allowed)
				(vias not_allowed)
				(pads allowed)
				(copperpour not_allowed)
				(footprints allowed)
			)
			(placement
				(enabled no)
				(sheetname "")
			)
			(fill
				(thermal_gap 0.5)
				(thermal_bridge_width 0.5)
				(island_removal_mode 0)
			)
			(polygon
				(pts
					(xy 362.461556 -121.138442) (xy 362.461556 -121.646442) (xy 362.080556 -121.646442) (xy 362.080556 -121.138442)
				)
			)
		)
	)
)
